(kicad_pcb
	(version 20260206)
	(generator "pcbnew")
	(generator_version "10.0")
	(general
		(thickness 1.6)
		(legacy_teardrops no)
	)
	(paper "A4")
	(title_block
		(title "04192023_DAF0TMB3IC0_F0TG_MB_C_brd_V02_OCP.brd")
		(comment 1 "Grand Teton / footprints 2692-2695 of 8354")
	)
	(layers
		(0 "F.Cu" signal "TOP")
		(4 "In1.Cu" signal "GND")
		(6 "In2.Cu" signal "IN1")
		(8 "In3.Cu" signal "GND1")
		(10 "In4.Cu" signal "IN2")
		(12 "In5.Cu" signal "GND2")
		(14 "In6.Cu" signal "IN3")
		(16 "In7.Cu" signal "GND3")
		(18 "In8.Cu" signal "VCC")
		(20 "In9.Cu" signal "VCC1")
		(22 "In10.Cu" signal "GND4")
		(24 "In11.Cu" signal "IN4")
		(26 "In12.Cu" signal "GND5")
		(28 "In13.Cu" signal "IN5")
		(30 "In14.Cu" signal "GND6")
		(32 "In15.Cu" signal "IN6")
		(34 "In16.Cu" signal "GND7")
		(2 "B.Cu" signal "BOTTOM")
		(9 "F.Adhes" user "F.Adhesive")
		(11 "B.Adhes" user "B.Adhesive")
		(13 "F.Paste" user "Package Geometry/Pastemask Top")
		(15 "B.Paste" user "Package Geometry/Pastemask Bottom")
		(5 "F.SilkS" user "Ref Des/Silkscreen Top")
		(7 "B.SilkS" user "Ref Des/Silkscreen Bottom")
		(1 "F.Mask" user "Board Geometry/Soldermask Top")
		(3 "B.Mask" user "Board Geometry/Soldermask Bottom")
		(17 "Dwgs.User" user "User.Drawings")
		(19 "Cmts.User" user "User.Comments")
		(21 "Eco1.User" user "User.Eco1")
		(23 "Eco2.User" user "User.Eco2")
		(25 "Edge.Cuts" user "Board Geometry/Outline")
		(27 "Margin" user)
		(31 "F.CrtYd" user "Package Geometry/Place Bound Top")
		(29 "B.CrtYd" user "Package Geometry/Place Bound Bottom")
		(35 "F.Fab" user "Ref Des/Assembly Top")
		(33 "B.Fab" user "Ref Des/Assembly Bottom")
	)
	(footprint ""
		(layer "F.Cu")
		(at 212.471508 -5.077206)
		(property "Reference" "J78"
			(at -4.352036 0.945388 90)
			(unlocked yes)
			(layer "F.SilkS")
			(effects
				(font
					(size 0.7874 0.5842)
					(thickness 0.1524)
				)
				(justify left)
			)
		)
		(property "Value" ""
			(at 0 0 0)
			(layer "F.Fab")
			(effects
				(font
					(size 1.27 1.27)
				)
			)
		)
		(duplicate_pad_numbers_are_jumpers no)
		(fp_line
			(start -1.2192 -2.06756)
			(end 1.2192 -2.06756)
			(stroke
				(width 0.1524)
				(type default)
			)
			(layer "F.SilkS")
		)
		(fp_line
			(start -1.2192 2.06756)
			(end -1.2192 -2.06756)
			(stroke
				(width 0.1524)
				(type default)
			)
			(layer "F.SilkS")
		)
		(fp_line
			(start 1.2192 -2.06756)
			(end 1.2192 2.06756)
			(stroke
				(width 0.1524)
				(type default)
			)
			(layer "F.SilkS")
		)
		(fp_line
			(start 1.2192 2.06756)
			(end -1.2192 2.06756)
			(stroke
				(width 0.1524)
				(type default)
			)
			(layer "F.SilkS")
		)
		(pad "" np_thru_hole circle
			(at -2.8829 -1.27 270)
			(size 1.0414 1.0414)
			(drill 1.0414)
			(layers "*.Cu" "*.Mask")
			(clearance 0.381)
			(thermal_gap 0.381)
		)
		(pad "" np_thru_hole circle
			(at -2.8829 1.27 270)
			(size 1.0414 1.0414)
			(drill 1.0414)
			(layers "*.Cu" "*.Mask")
			(clearance 0.381)
			(thermal_gap 0.381)
		)
		(pad "" np_thru_hole circle
			(at 3.4671 -1.27 270)
			(size 1.0414 1.0414)
			(drill 1.0414)
			(layers "*.Cu" "*.Mask")
			(clearance 0.381)
			(thermal_gap 0.381)
		)
		(pad "" np_thru_hole circle
			(at 3.4671 1.27 270)
			(size 1.0414 1.0414)
			(drill 1.0414)
			(layers "*.Cu" "*.Mask")
			(clearance 0.381)
			(thermal_gap 0.381)
		)
		(pad "1" smd rect
			(at 0.8255 -0.249936 270)
			(size 0.3048 0.508)
			(layers "F.Cu" "F.Mask" "F.Paste")
			(net "DELTA_L_85_10INCH_IN2_DP")
		)
		(pad "2" smd rect
			(at 0.8255 0.249936 270)
			(size 0.3048 0.508)
			(layers "F.Cu" "F.Mask" "F.Paste")
			(net "DELTA_L_85_10INCH_IN2_DN")
		)
		(pad "3" smd circle
			(at 0 0)
			(size 0 0)
			(layers "F.Cu" "F.Mask" "F.Paste")
			(net "DELTA_L_GND_1")
		)
		(zone
			(layer "F.Cu")
			(hatch none 0.5)
			(connect_pads
				(clearance 0)
			)
			(min_thickness 0.25)
			(keepout
				(tracks not_allowed)
				(vias allowed)
				(pads allowed)
				(copperpour not_allowed)
				(footprints allowed)
			)
			(placement
				(enabled no)
				(sheetname "")
			)
			(fill
				(thermal_gap 0.5)
				(thermal_bridge_width 0.5)
				(island_removal_mode 0)
			)
			(polygon
				(pts
					(xy 213.589108 -5.625846) (xy 213.589108 -5.530342) (xy 212.992208 -5.530342) (xy 212.992208 -5.123942)
					(xy 213.589108 -5.123942) (xy 213.589108 -5.03047) (xy 212.992208 -5.03047) (xy 212.992208 -4.62407)
					(xy 213.589108 -4.62407) (xy 213.589108 -4.528566) (xy 212.890608 -4.528566) (xy 212.890608 -5.625846)
				)
			)
		)
		(zone
			(layers "F.Cu" "B.Cu" "In1.Cu" "In2.Cu" "In3.Cu" "In4.Cu" "In5.Cu" "In6.Cu"
				"In7.Cu" "In8.Cu" "In9.Cu" "In10.Cu" "In11.Cu" "In12.Cu" "In13.Cu" "In14.Cu"
				"In15.Cu" "In16.Cu"
			)
			(hatch none 0.5)
			(connect_pads
				(clearance 0)
			)
			(min_thickness 0.25)
			(keepout
				(tracks not_allowed)
				(vias allowed)
				(pads allowed)
				(copperpour not_allowed)
				(footprints allowed)
			)
			(placement
				(enabled no)
				(sheetname "")
			)
			(fill
				(thermal_gap 0.5)
				(thermal_bridge_width 0.5)
				(island_removal_mode 0)
			)
			(polygon
				(pts
					(arc
						(start 210.515708 -6.347206)
						(mid 208.661508 -6.347206)
						(end 210.515708 -6.347206)
					)
				)
			)
		)
		(zone
			(layers "F.Cu" "B.Cu" "In1.Cu" "In2.Cu" "In3.Cu" "In4.Cu" "In5.Cu" "In6.Cu"
				"In7.Cu" "In8.Cu" "In9.Cu" "In10.Cu" "In11.Cu" "In12.Cu" "In13.Cu" "In14.Cu"
				"In15.Cu" "In16.Cu"
			)
			(hatch none 0.5)
			(connect_pads
				(clearance 0)
			)
			(min_thickness 0.25)
			(keepout
				(tracks not_allowed)
				(vias allowed)
				(pads allowed)
				(copperpour not_allowed)
				(footprints allowed)
			)
			(placement
				(enabled no)
				(sheetname "")
			)
			(fill
				(thermal_gap 0.5)
				(thermal_bridge_width 0.5)
				(island_removal_mode 0)
			)
			(polygon
				(pts
					(arc
						(start 210.515708 -3.807206)
						(mid 208.661508 -3.807206)
						(end 210.515708 -3.807206)
					)
				)
			)
		)
		(zone
			(layers "F.Cu" "B.Cu" "In1.Cu" "In2.Cu" "In3.Cu" "In4.Cu" "In5.Cu" "In6.Cu"
				"In7.Cu" "In8.Cu" "In9.Cu" "In10.Cu" "In11.Cu" "In12.Cu" "In13.Cu" "In14.Cu"
				"In15.Cu" "In16.Cu"
			)
			(hatch none 0.5)
			(connect_pads
				(clearance 0)
			)
			(min_thickness 0.25)
			(keepout
				(tracks not_allowed)
				(vias allowed)
				(pads allowed)
				(copperpour not_allowed)
				(footprints allowed)
			)
			(placement
				(enabled no)
				(sheetname "")
			)
			(fill
				(thermal_gap 0.5)
				(thermal_bridge_width 0.5)
				(island_removal_mode 0)
			)
			(polygon
				(pts
					(arc
						(start 216.865708 -6.347206)
						(mid 215.011508 -6.347206)
						(end 216.865708 -6.347206)
					)
				)
			)
		)
		(zone
			(layers "F.Cu" "B.Cu" "In1.Cu" "In2.Cu" "In3.Cu" "In4.Cu" "In5.Cu" "In6.Cu"
				"In7.Cu" "In8.Cu" "In9.Cu" "In10.Cu" "In11.Cu" "In12.Cu" "In13.Cu" "In14.Cu"
				"In15.Cu" "In16.Cu"
			)
			(hatch none 0.5)
			(connect_pads
				(clearance 0)
			)
			(min_thickness 0.25)
			(keepout
				(tracks not_allowed)
				(vias allowed)
				(pads allowed)
				(copperpour not_allowed)
				(footprints allowed)
			)
			(placement
				(enabled no)
				(sheetname "")
			)
			(fill
				(thermal_gap 0.5)
				(thermal_bridge_width 0.5)
				(island_removal_mode 0)
			)
			(polygon
				(pts
					(arc
						(start 216.865708 -3.807206)
						(mid 215.011508 -3.807206)
						(end 216.865708 -3.807206)
					)
				)
			)
		)
	)
	(footprint ""
		(layer "F.Cu")
		(at 24.765 -366.903)
		(property "Reference" "R8248"
			(at 0 0 0)
			(layer "F.SilkS")
			(hide yes)
			(effects
				(font
					(size 1.27 1.27)
				)
			)
		)
		(property "Value" ""
			(at 0 0 0)
			(layer "F.Fab")
			(effects
				(font
					(size 1.27 1.27)
				)
			)
		)
		(duplicate_pad_numbers_are_jumpers no)
		(fp_line
			(start -0.7874 -0.4064)
			(end 0.7874 -0.4064)
			(stroke
				(width 0.1524)
				(type default)
			)
			(layer "F.SilkS")
		)
		(fp_line
			(start -0.7874 0.4064)
			(end -0.7874 -0.4064)
			(stroke
				(width 0.1524)
				(type default)
			)
			(layer "F.SilkS")
		)
		(fp_line
			(start 0.7874 -0.4064)
			(end 0.7874 0.4064)
			(stroke
				(width 0.1524)
				(type default)
			)
			(layer "F.SilkS")
		)
		(fp_line
			(start 0.7874 0.4064)
			(end -0.7874 0.4064)
			(stroke
				(width 0.1524)
				(type default)
			)
			(layer "F.SilkS")
		)
		(fp_line
			(start -0.67945 -0.305054)
			(end -0.12065 -0.305054)
			(stroke
				(width 0.1)
				(type default)
			)
			(layer "F.Fab")
		)
		(fp_line
			(start -0.67945 0.3048)
			(end -0.67945 -0.305054)
			(stroke
				(width 0.1)
				(type default)
			)
			(layer "F.Fab")
		)
		(fp_line
			(start -0.12065 -0.305054)
			(end -0.12065 -0.2794)
			(stroke
				(width 0.1)
				(type default)
			)
			(layer "F.Fab")
		)
		(fp_line
			(start -0.12065 -0.2794)
			(end 0.12065 -0.2794)
			(stroke
				(width 0.1)
				(type default)
			)
			(layer "F.Fab")
		)
		(fp_line
			(start -0.12065 0.2794)
			(end -0.12065 0.3048)
			(stroke
				(width 0.1)
				(type default)
			)
			(layer "F.Fab")
		)
		(fp_line
			(start -0.12065 0.3048)
			(end -0.67945 0.3048)
			(stroke
				(width 0.1)
				(type default)
			)
			(layer "F.Fab")
		)
		(fp_line
			(start 0.120396 0.2794)
			(end -0.12065 0.2794)
			(stroke
				(width 0.1)
				(type default)
			)
			(layer "F.Fab")
		)
		(fp_line
			(start 0.120396 0.3048)
			(end 0.120396 0.2794)
			(stroke
				(width 0.1)
				(type default)
			)
			(layer "F.Fab")
		)
		(fp_line
			(start 0.12065 -0.3048)
			(end 0.67945 -0.3048)
			(stroke
				(width 0.1)
				(type default)
			)
			(layer "F.Fab")
		)
		(fp_line
			(start 0.12065 -0.2794)
			(end 0.12065 -0.3048)
			(stroke
				(width 0.1)
				(type default)
			)
			(layer "F.Fab")
		)
		(fp_line
			(start 0.67945 -0.3048)
			(end 0.67945 0.3048)
			(stroke
				(width 0.1)
				(type default)
			)
			(layer "F.Fab")
		)
		(fp_line
			(start 0.67945 0.3048)
			(end 0.120396 0.3048)
			(stroke
				(width 0.1)
				(type default)
			)
			(layer "F.Fab")
		)
		(pad "1" smd circle
			(at -0.40005 0)
			(size 0 0)
			(layers "F.Cu" "F.Mask" "F.Paste")
			(net "SMB_SCM_2_R1_SCL")
		)
		(pad "2" smd circle
			(at 0.40005 0)
			(size 0 0)
			(layers "F.Cu" "F.Mask" "F.Paste")
			(net "SMB_CLK_PVDDCR_CPU1_P1_R")
		)
	)
	(footprint ""
		(layer "F.Cu")
		(at 164.143944 -344.153998 -90)
		(property "Reference" "PR13"
			(at 0 0 270)
			(layer "F.SilkS")
			(hide yes)
			(effects
				(font
					(size 1.27 1.27)
				)
			)
		)
		(property "Value" ""
			(at 0 0 270)
			(layer "F.Fab")
			(effects
				(font
					(size 1.27 1.27)
				)
			)
		)
		(duplicate_pad_numbers_are_jumpers no)
		(fp_line
			(start -0.7874 0.4064)
			(end -0.7874 -0.4064)
			(stroke
				(width 0.1524)
				(type default)
			)
			(layer "F.SilkS")
		)
		(fp_line
			(start 0.7874 0.4064)
			(end -0.7874 0.4064)
			(stroke
				(width 0.1524)
				(type default)
			)
			(layer "F.SilkS")
		)
		(fp_line
			(start -0.7874 -0.4064)
			(end 0.7874 -0.4064)
			(stroke
				(width 0.1524)
				(type default)
			)
			(layer "F.SilkS")
		)
		(fp_line
			(start 0.7874 -0.4064)
			(end 0.7874 0.4064)
			(stroke
				(width 0.1524)
				(type default)
			)
			(layer "F.SilkS")
		)
		(fp_line
			(start -0.67945 0.3048)
			(end -0.67945 -0.305054)
			(stroke
				(width 0.1)
				(type default)
			)
			(layer "F.Fab")
		)
		(fp_line
			(start -0.12065 0.3048)
			(end -0.67945 0.3048)
			(stroke
				(width 0.1)
				(type default)
			)
			(layer "F.Fab")
		)
		(fp_line
			(start 0.120396 0.3048)
			(end 0.120396 0.2794)
			(stroke
				(width 0.1)
				(type default)
			)
			(layer "F.Fab")
		)
		(fp_line
			(start 0.67945 0.3048)
			(end 0.120396 0.3048)
			(stroke
				(width 0.1)
				(type default)
			)
			(layer "F.Fab")
		)
		(fp_line
			(start -0.12065 0.2794)
			(end -0.12065 0.3048)
			(stroke
				(width 0.1)
				(type default)
			)
			(layer "F.Fab")
		)
		(fp_line
			(start 0.120396 0.2794)
			(end -0.12065 0.2794)
			(stroke
				(width 0.1)
				(type default)
			)
			(layer "F.Fab")
		)
		(fp_line
			(start -0.12065 -0.2794)
			(end 0.12065 -0.2794)
			(stroke
				(width 0.1)
				(type default)
			)
			(layer "F.Fab")
		)
		(fp_line
			(start 0.12065 -0.2794)
			(end 0.12065 -0.3048)
			(stroke
				(width 0.1)
				(type default)
			)
			(layer "F.Fab")
		)
		(fp_line
			(start 0.12065 -0.3048)
			(end 0.67945 -0.3048)
			(stroke
				(width 0.1)
				(type default)
			)
			(layer "F.Fab")
		)
		(fp_line
			(start 0.67945 -0.3048)
			(end 0.67945 0.3048)
			(stroke
				(width 0.1)
				(type default)
			)
			(layer "F.Fab")
		)
		(fp_line
			(start -0.67945 -0.305054)
			(end -0.12065 -0.305054)
			(stroke
				(width 0.1)
				(type default)
			)
			(layer "F.Fab")
		)
		(fp_line
			(start -0.12065 -0.305054)
			(end -0.12065 -0.2794)
			(stroke
				(width 0.1)
				(type default)
			)
			(layer "F.Fab")
		)
		(pad "1" smd circle
			(at -0.40005 0 270)
			(size 0 0)
			(layers "F.Cu" "F.Mask" "F.Paste")
			(net "NC_PVDD11_S3_P1_IMON5")
		)
		(pad "2" smd circle
			(at 0.40005 0 270)
			(size 0 0)
			(layers "F.Cu" "F.Mask" "F.Paste")
			(net "GND")
		)
	)
	(footprint ""
		(layer "F.Cu")
		(at 61.90488 -19.268948 180)
		(property "Reference" "R3164"
			(at 0 0 180)
			(layer "F.SilkS")
			(hide yes)
			(effects
				(font
					(size 1.27 1.27)
				)
			)
		)
		(property "Value" ""
			(at 0 0 180)
			(layer "F.Fab")
			(effects
				(font
					(size 1.27 1.27)
				)
			)
		)
		(duplicate_pad_numbers_are_jumpers no)
		(fp_line
			(start 0.7874 0.4064)
			(end -0.7874 0.4064)
			(stroke
				(width 0.1524)
				(type default)
			)
			(layer "F.SilkS")
		)
		(fp_line
			(start 0.7874 -0.4064)
			(end 0.7874 0.4064)
			(stroke
				(width 0.1524)
				(type default)
			)
			(layer "F.SilkS")
		)
		(fp_line
			(start -0.7874 0.4064)
			(end -0.7874 -0.4064)
			(stroke
				(width 0.1524)
				(type default)
			)
			(layer "F.SilkS")
		)
		(fp_line
			(start -0.7874 -0.4064)
			(end 0.7874 -0.4064)
			(stroke
				(width 0.1524)
				(type default)
			)
			(layer "F.SilkS")
		)
		(fp_line
			(start 0.67945 0.3048)
			(end 0.120396 0.3048)
			(stroke
				(width 0.1)
				(type default)
			)
			(layer "F.Fab")
		)
		(fp_line
			(start 0.67945 -0.3048)
			(end 0.67945 0.3048)
			(stroke
				(width 0.1)
				(type default)
			)
			(layer "F.Fab")
		)
		(fp_line
			(start 0.12065 -0.2794)
			(end 0.12065 -0.3048)
			(stroke
				(width 0.1)
				(type default)
			)
			(layer "F.Fab")
		)
		(fp_line
			(start 0.12065 -0.3048)
			(end 0.67945 -0.3048)
			(stroke
				(width 0.1)
				(type default)
			)
			(layer "F.Fab")
		)
		(fp_line
			(start 0.120396 0.3048)
			(end 0.120396 0.2794)
			(stroke
				(width 0.1)
				(type default)
			)
			(layer "F.Fab")
		)
		(fp_line
			(start 0.120396 0.2794)
			(end -0.12065 0.2794)
			(stroke
				(width 0.1)
				(type default)
			)
			(layer "F.Fab")
		)
		(fp_line
			(start -0.12065 0.3048)
			(end -0.67945 0.3048)
			(stroke
				(width 0.1)
				(type default)
			)
			(layer "F.Fab")
		)
		(fp_line
			(start -0.12065 0.2794)
			(end -0.12065 0.3048)
			(stroke
				(width 0.1)
				(type default)
			)
			(layer "F.Fab")
		)
		(fp_line
			(start -0.12065 -0.2794)
			(end 0.12065 -0.2794)
			(stroke
				(width 0.1)
				(type default)
			)
			(layer "F.Fab")
		)
		(fp_line
			(start -0.12065 -0.305054)
			(end -0.12065 -0.2794)
			(stroke
				(width 0.1)
				(type default)
			)
			(layer "F.Fab")
		)
		(fp_line
			(start -0.67945 0.3048)
			(end -0.67945 -0.305054)
			(stroke
				(width 0.1)
				(type default)
			)
			(layer "F.Fab")
		)
		(fp_line
			(start -0.67945 -0.305054)
			(end -0.12065 -0.305054)
			(stroke
				(width 0.1)
				(type default)
			)
			(layer "F.Fab")
		)
		(pad "1" smd circle
			(at -0.40005 0 180)
			(size 0 0)
			(layers "F.Cu" "F.Mask" "F.Paste")
			(net "GND")
		)
		(pad "2" smd circle
			(at 0.40005 0 180)
			(size 0 0)
			(layers "F.Cu" "F.Mask" "F.Paste")
			(net "OCP_V3_2_AUX_PWR_EN")
		)
	)
)
